(kicad_pcb
	(version 20260206)
	(generator "pcbnew")
	(generator_version "10.0")
	(general
		(thickness 1.6)
		(legacy_teardrops no)
	)
	(paper "A4")
	(title_block
		(title "dpb — 14545-sa.0730WZS0815.brd")
		(comment 1 "Honey Badger (Wiwynn) / footprints 184-189 of 1066")
	)
	(layers
		(0 "F.Cu" signal "TOP")
		(4 "In1.Cu" signal "L2GND")
		(6 "In2.Cu" signal "L3")
		(8 "In3.Cu" signal "L4VCC")
		(10 "In4.Cu" signal "L5VCC")
		(12 "In5.Cu" signal "L6")
		(14 "In6.Cu" signal "L7GND")
		(2 "B.Cu" signal "BOTTOM")
		(9 "F.Adhes" user "F.Adhesive")
		(11 "B.Adhes" user "B.Adhesive")
		(13 "F.Paste" user "Package Geometry/Pastemask Top")
		(15 "B.Paste" user "Package Geometry/Pastemask Bottom")
		(5 "F.SilkS" user "Ref Des/Silkscreen Top")
		(7 "B.SilkS" user "Ref Des/Silkscreen Bottom")
		(1 "F.Mask" user "Board Geometry/Soldermask Top")
		(3 "B.Mask" user "Board Geometry/Soldermask Bottom")
		(17 "Dwgs.User" user "User.Drawings")
		(19 "Cmts.User" user "User.Comments")
		(21 "Eco1.User" user "User.Eco1")
		(23 "Eco2.User" user "User.Eco2")
		(25 "Edge.Cuts" user "Board Geometry/Outline")
		(27 "Margin" user)
		(31 "F.CrtYd" user "Package Geometry/Place Bound Top")
		(29 "B.CrtYd" user "Package Geometry/Place Bound Bottom")
		(35 "F.Fab" user "Ref Des/Assembly Top")
		(33 "B.Fab" user "Ref Des/Assembly Bottom")
	)
	(footprint ""
		(layer "F.Cu")
		(at 10.159746 -466.8647 90)
		(property "Reference" "R391"
			(at 0 0 90)
			(layer "F.SilkS")
			(hide yes)
			(effects
				(font
					(size 1.27 1.27)
				)
			)
		)
		(property "Value" "0R2J-2-GP"
			(at 0.064008 -3.993896 90)
			(unlocked yes)
			(layer "F.Fab")
			(hide yes)
			(effects
				(font
					(size 1.016 1.016)
					(thickness 0.1524)
				)
			)
		)
		(property "Device Type" "R402H16"
			(at 0.064008 -5.517896 90)
			(unlocked yes)
			(layer "F.Fab")
			(hide yes)
			(effects
				(font
					(size 1.016 1.016)
					(thickness 0.1524)
				)
			)
		)
		(duplicate_pad_numbers_are_jumpers no)
		(fp_line
			(start 0.508 -0.9398)
			(end -0.508 -0.9398)
			(stroke
				(width 0.1524)
				(type default)
			)
			(layer "F.SilkS")
		)
		(fp_line
			(start -0.508 -0.9398)
			(end -0.508 0.9398)
			(stroke
				(width 0.1524)
				(type default)
			)
			(layer "F.SilkS")
		)
		(fp_rect
			(start -0.508 0.9398)
			(end 0.508 -0.9398)
			(stroke
				(width 0)
				(type default)
			)
			(fill no)
			(layer "F.CrtYd")
		)
		(fp_rect
			(start -0.508 0.9398)
			(end 0.508 -0.9398)
			(stroke
				(width 0)
				(type default)
			)
			(fill no)
			(layer "F.Fab")
		)
		(pad "1" smd custom
			(at 0 -0.4445 90)
			(size 0.1397 0.1397)
			(layers "F.Cu" "F.Mask" "F.Paste")
			(net "EXP_B_PRNST_RX")
			(options
				(clearance outline)
				(anchor circle)
			)
			(primitives
				(gr_poly
					(pts
						(arc
							(start -0.1778 -0.2794)
							(mid -0.249642 -0.249642)
							(end -0.2794 -0.1778)
						)
						(arc
							(start -0.2794 0.1778)
							(mid -0.249642 0.249642)
							(end -0.1778 0.2794)
						)
						(arc
							(start 0.1778 0.2794)
							(mid 0.249642 0.249642)
							(end 0.2794 0.1778)
						)
						(arc
							(start 0.2794 -0.1778)
							(mid 0.249642 -0.249642)
							(end 0.1778 -0.2794)
						)
					)
					(width 0)
					(fill yes)
				)
			)
		)
		(pad "2" smd custom
			(at 0 0.4445 90)
			(size 0.1397 0.1397)
			(layers "F.Cu" "F.Mask" "F.Paste")
			(net "EXP_B_PRNST_TX")
			(options
				(clearance outline)
				(anchor circle)
			)
			(primitives
				(gr_poly
					(pts
						(arc
							(start -0.1778 -0.2794)
							(mid -0.249642 -0.249642)
							(end -0.2794 -0.1778)
						)
						(arc
							(start -0.2794 0.1778)
							(mid -0.249642 0.249642)
							(end -0.1778 0.2794)
						)
						(arc
							(start 0.1778 0.2794)
							(mid 0.249642 0.249642)
							(end 0.2794 0.1778)
						)
						(arc
							(start 0.2794 -0.1778)
							(mid 0.249642 -0.249642)
							(end 0.1778 -0.2794)
						)
					)
					(width 0)
					(fill yes)
				)
			)
		)
	)
	(footprint ""
		(layer "F.Cu")
		(at 9.1186 -465.5058)
		(property "Reference" "TP18"
			(at 0 0 0)
			(layer "F.SilkS")
			(hide yes)
			(effects
				(font
					(size 1.27 1.27)
				)
			)
		)
		(property "Value" "TPAD32-GP"
			(at 0 -3.166364 0)
			(unlocked yes)
			(layer "F.Fab")
			(hide yes)
			(effects
				(font
					(size 1.016 1.016)
					(thickness 0.1524)
				)
			)
		)
		(property "Device Type" "TPAD32"
			(at 0 -4.690618 0)
			(unlocked yes)
			(layer "F.Fab")
			(hide yes)
			(effects
				(font
					(size 1.016 1.016)
					(thickness 0.1524)
				)
			)
		)
		(duplicate_pad_numbers_are_jumpers no)
		(fp_poly
			(pts
				(arc
					(start 0.4064 0)
					(mid -0.4064 0)
					(end 0.4064 0)
				)
			)
			(stroke
				(width 0)
				(type default)
			)
			(fill no)
			(layer "F.CrtYd")
		)
		(fp_poly
			(pts
				(arc
					(start 0.7112 0)
					(mid -0.7112 0)
					(end 0.7112 0)
				)
			)
			(stroke
				(width 0)
				(type default)
			)
			(fill no)
			(layer "F.Fab")
		)
		(pad "1" smd circle
			(at 0 0)
			(size 0.8128 0.8128)
			(layers "F.Cu" "F.Mask" "F.Paste")
			(net "SAS_EXP_A_PWR15")
		)
	)
	(footprint ""
		(layer "F.Cu")
		(at 57.276746 -381.2667)
		(property "Reference" "R189"
			(at 0 0 0)
			(layer "F.SilkS")
			(hide yes)
			(effects
				(font
					(size 1.27 1.27)
				)
			)
		)
		(property "Value" "4K7R2J-2-GP"
			(at 0.064008 -3.993896 0)
			(unlocked yes)
			(layer "F.Fab")
			(hide yes)
			(effects
				(font
					(size 1.016 1.016)
					(thickness 0.1524)
				)
			)
		)
		(property "Device Type" "R402H16"
			(at 0.064008 -5.517896 0)
			(unlocked yes)
			(layer "F.Fab")
			(hide yes)
			(effects
				(font
					(size 1.016 1.016)
					(thickness 0.1524)
				)
			)
		)
		(duplicate_pad_numbers_are_jumpers no)
		(fp_line
			(start -0.508 -0.9398)
			(end -0.508 0.9398)
			(stroke
				(width 0.1524)
				(type default)
			)
			(layer "F.SilkS")
		)
		(fp_line
			(start 0.508 -0.9398)
			(end -0.508 -0.9398)
			(stroke
				(width 0.1524)
				(type default)
			)
			(layer "F.SilkS")
		)
		(fp_rect
			(start -0.508 0.9398)
			(end 0.508 -0.9398)
			(stroke
				(width 0)
				(type default)
			)
			(fill no)
			(layer "F.CrtYd")
		)
		(fp_rect
			(start -0.508 0.9398)
			(end 0.508 -0.9398)
			(stroke
				(width 0)
				(type default)
			)
			(fill no)
			(layer "F.Fab")
		)
		(pad "1" smd custom
			(at 0 -0.4445)
			(size 0.1397 0.1397)
			(layers "F.Cu" "F.Mask" "F.Paste")
			(net "P3V3")
			(options
				(clearance outline)
				(anchor circle)
			)
			(primitives
				(gr_poly
					(pts
						(arc
							(start -0.1778 -0.2794)
							(mid -0.249642 -0.249642)
							(end -0.2794 -0.1778)
						)
						(arc
							(start -0.2794 0.1778)
							(mid -0.249642 0.249642)
							(end -0.1778 0.2794)
						)
						(arc
							(start 0.1778 0.2794)
							(mid 0.249642 0.249642)
							(end 0.2794 0.1778)
						)
						(arc
							(start 0.2794 -0.1778)
							(mid 0.249642 -0.249642)
							(end 0.1778 -0.2794)
						)
					)
					(width 0)
					(fill yes)
				)
			)
		)
		(pad "2" smd custom
			(at 0 0.4445)
			(size 0.1397 0.1397)
			(layers "F.Cu" "F.Mask" "F.Paste")
			(net "HDD_PRSNT_NET6")
			(options
				(clearance outline)
				(anchor circle)
			)
			(primitives
				(gr_poly
					(pts
						(arc
							(start -0.1778 -0.2794)
							(mid -0.249642 -0.249642)
							(end -0.2794 -0.1778)
						)
						(arc
							(start -0.2794 0.1778)
							(mid -0.249642 0.249642)
							(end -0.1778 0.2794)
						)
						(arc
							(start 0.1778 0.2794)
							(mid 0.249642 0.249642)
							(end 0.2794 0.1778)
						)
						(arc
							(start 0.2794 -0.1778)
							(mid 0.249642 -0.249642)
							(end 0.1778 -0.2794)
						)
					)
					(width 0)
					(fill yes)
				)
			)
		)
	)
	(footprint ""
		(layer "F.Cu")
		(at 44.322746 -419.446202)
		(property "Reference" "R252"
			(at 0 0 0)
			(layer "F.SilkS")
			(hide yes)
			(effects
				(font
					(size 1.27 1.27)
				)
			)
		)
		(property "Value" "0R2J-2-GP"
			(at 0.064008 -3.993896 0)
			(unlocked yes)
			(layer "F.Fab")
			(hide yes)
			(effects
				(font
					(size 1.016 1.016)
					(thickness 0.1524)
				)
			)
		)
		(property "Device Type" "R402H16"
			(at 0.064008 -5.517896 0)
			(unlocked yes)
			(layer "F.Fab")
			(hide yes)
			(effects
				(font
					(size 1.016 1.016)
					(thickness 0.1524)
				)
			)
		)
		(duplicate_pad_numbers_are_jumpers no)
		(fp_line
			(start -0.508 -0.9398)
			(end -0.508 0.9398)
			(stroke
				(width 0.1524)
				(type default)
			)
			(layer "F.SilkS")
		)
		(fp_line
			(start 0.508 -0.9398)
			(end -0.508 -0.9398)
			(stroke
				(width 0.1524)
				(type default)
			)
			(layer "F.SilkS")
		)
		(fp_rect
			(start -0.508 0.9398)
			(end 0.508 -0.9398)
			(stroke
				(width 0)
				(type default)
			)
			(fill no)
			(layer "F.CrtYd")
		)
		(fp_rect
			(start -0.508 0.9398)
			(end 0.508 -0.9398)
			(stroke
				(width 0)
				(type default)
			)
			(fill no)
			(layer "F.Fab")
		)
		(pad "1" smd custom
			(at 0 -0.4445)
			(size 0.1397 0.1397)
			(layers "F.Cu" "F.Mask" "F.Paste")
			(net "SW_PWR_HDD10")
			(options
				(clearance outline)
				(anchor circle)
			)
			(primitives
				(gr_poly
					(pts
						(arc
							(start -0.1778 -0.2794)
							(mid -0.249642 -0.249642)
							(end -0.2794 -0.1778)
						)
						(arc
							(start -0.2794 0.1778)
							(mid -0.249642 0.249642)
							(end -0.1778 0.2794)
						)
						(arc
							(start 0.1778 0.2794)
							(mid 0.249642 0.249642)
							(end 0.2794 0.1778)
						)
						(arc
							(start 0.2794 -0.1778)
							(mid 0.249642 -0.249642)
							(end 0.1778 -0.2794)
						)
					)
					(width 0)
					(fill yes)
				)
			)
		)
		(pad "2" smd custom
			(at 0 0.4445)
			(size 0.1397 0.1397)
			(layers "F.Cu" "F.Mask" "F.Paste")
			(net "SW_PWR_R_HDD10")
			(options
				(clearance outline)
				(anchor circle)
			)
			(primitives
				(gr_poly
					(pts
						(arc
							(start -0.1778 -0.2794)
							(mid -0.249642 -0.249642)
							(end -0.2794 -0.1778)
						)
						(arc
							(start -0.2794 0.1778)
							(mid -0.249642 0.249642)
							(end -0.1778 0.2794)
						)
						(arc
							(start 0.1778 0.2794)
							(mid 0.249642 0.249642)
							(end 0.2794 0.1778)
						)
						(arc
							(start 0.2794 -0.1778)
							(mid 0.249642 -0.249642)
							(end 0.1778 -0.2794)
						)
					)
					(width 0)
					(fill yes)
				)
			)
		)
	)
	(footprint ""
		(layer "F.Cu")
		(at 93.091 -21.463)
		(property "Reference" "C378"
			(at 0 0 0)
			(layer "F.SilkS")
			(hide yes)
			(effects
				(font
					(size 1.27 1.27)
				)
			)
		)
		(property "Value" "SCD033U25V2KX-GP"
			(at 1.1811 -2.7051 0)
			(unlocked yes)
			(layer "F.Fab")
			(hide yes)
			(effects
				(font
					(size 1.016 1.016)
					(thickness 0.1524)
				)
			)
		)
		(property "Device Type" "C402H22"
			(at 1.1811 -4.2291 0)
			(unlocked yes)
			(layer "F.Fab")
			(hide yes)
			(effects
				(font
					(size 1.016 1.016)
					(thickness 0.1524)
				)
			)
		)
		(duplicate_pad_numbers_are_jumpers no)
		(fp_rect
			(start -0.4318 0.9525)
			(end 0.4318 -0.9525)
			(stroke
				(width 0)
				(type default)
			)
			(fill no)
			(layer "F.CrtYd")
		)
		(fp_rect
			(start -0.4318 0.9525)
			(end 0.4318 -0.9525)
			(stroke
				(width 0)
				(type default)
			)
			(fill no)
			(layer "F.Fab")
		)
		(pad "1" smd custom
			(at 0 -0.4445)
			(size 0.1524 0.1524)
			(layers "F.Cu" "F.Mask" "F.Paste")
			(net "SW_HDD14_P")
			(options
				(clearance outline)
				(anchor circle)
			)
			(primitives
				(gr_poly
					(pts
						(arc
							(start 0.3048 -0.2032)
							(mid 0.275042 -0.275042)
							(end 0.2032 -0.3048)
						)
						(arc
							(start -0.2032 -0.3048)
							(mid -0.275042 -0.275042)
							(end -0.3048 -0.2032)
						)
						(arc
							(start -0.3048 0.2032)
							(mid -0.275042 0.275042)
							(end -0.2032 0.3048)
						)
						(arc
							(start 0.2032 0.3048)
							(mid 0.275042 0.275042)
							(end 0.3048 0.2032)
						)
					)
					(width 0)
					(fill yes)
				)
			)
		)
		(pad "2" smd custom
			(at 0 0.4445)
			(size 0.1524 0.1524)
			(layers "F.Cu" "F.Mask" "F.Paste")
			(net "GND")
			(options
				(clearance outline)
				(anchor circle)
			)
			(primitives
				(gr_poly
					(pts
						(arc
							(start 0.3048 -0.2032)
							(mid 0.275042 -0.275042)
							(end 0.2032 -0.3048)
						)
						(arc
							(start -0.2032 -0.3048)
							(mid -0.275042 -0.275042)
							(end -0.3048 -0.2032)
						)
						(arc
							(start -0.3048 0.2032)
							(mid -0.275042 0.275042)
							(end -0.2032 0.3048)
						)
						(arc
							(start 0.2032 0.3048)
							(mid 0.275042 0.275042)
							(end 0.3048 0.2032)
						)
					)
					(width 0)
					(fill yes)
				)
			)
		)
	)
	(footprint ""
		(layer "F.Cu")
		(at 233.806746 -27.9527)
		(property "Reference" "PR2"
			(at 0 0 0)
			(layer "F.SilkS")
			(hide yes)
			(effects
				(font
					(size 1.27 1.27)
				)
			)
		)
		(property "Value" "10KR2F-2-GP"
			(at 0.064008 -3.993896 0)
			(unlocked yes)
			(layer "F.Fab")
			(hide yes)
			(effects
				(font
					(size 1.016 1.016)
					(thickness 0.1524)
				)
			)
		)
		(property "Device Type" "R402H16"
			(at 0.064008 -5.517896 0)
			(unlocked yes)
			(layer "F.Fab")
			(hide yes)
			(effects
				(font
					(size 1.016 1.016)
					(thickness 0.1524)
				)
			)
		)
		(duplicate_pad_numbers_are_jumpers no)
		(fp_line
			(start -0.508 -0.9398)
			(end -0.508 0.9398)
			(stroke
				(width 0.1524)
				(type default)
			)
			(layer "F.SilkS")
		)
		(fp_line
			(start 0.508 -0.9398)
			(end -0.508 -0.9398)
			(stroke
				(width 0.1524)
				(type default)
			)
			(layer "F.SilkS")
		)
		(fp_rect
			(start -0.508 0.9398)
			(end 0.508 -0.9398)
			(stroke
				(width 0)
				(type default)
			)
			(fill no)
			(layer "F.CrtYd")
		)
		(fp_rect
			(start -0.508 0.9398)
			(end 0.508 -0.9398)
			(stroke
				(width 0)
				(type default)
			)
			(fill no)
			(layer "F.Fab")
		)
		(pad "1" smd custom
			(at 0 -0.4445)
			(size 0.1397 0.1397)
			(layers "F.Cu" "F.Mask" "F.Paste")
			(net "P5VA_12VIN")
			(options
				(clearance outline)
				(anchor circle)
			)
			(primitives
				(gr_poly
					(pts
						(arc
							(start -0.1778 -0.2794)
							(mid -0.249642 -0.249642)
							(end -0.2794 -0.1778)
						)
						(arc
							(start -0.2794 0.1778)
							(mid -0.249642 0.249642)
							(end -0.1778 0.2794)
						)
						(arc
							(start 0.1778 0.2794)
							(mid 0.249642 0.249642)
							(end 0.2794 0.1778)
						)
						(arc
							(start 0.2794 -0.1778)
							(mid 0.249642 -0.249642)
							(end 0.1778 -0.2794)
						)
					)
					(width 0)
					(fill yes)
				)
			)
		)
		(pad "2" smd custom
			(at 0 0.4445)
			(size 0.1397 0.1397)
			(layers "F.Cu" "F.Mask" "F.Paste")
			(net "P5VA_EN")
			(options
				(clearance outline)
				(anchor circle)
			)
			(primitives
				(gr_poly
					(pts
						(arc
							(start -0.1778 -0.2794)
							(mid -0.249642 -0.249642)
							(end -0.2794 -0.1778)
						)
						(arc
							(start -0.2794 0.1778)
							(mid -0.249642 0.249642)
							(end -0.1778 0.2794)
						)
						(arc
							(start 0.1778 0.2794)
							(mid 0.249642 0.249642)
							(end 0.2794 0.1778)
						)
						(arc
							(start 0.2794 -0.1778)
							(mid 0.249642 -0.249642)
							(end 0.1778 -0.2794)
						)
					)
					(width 0)
					(fill yes)
				)
			)
		)
	)
)
